# T6G (Grand Teton) — schematic netlist excerpt (pin names and nets, part order shuffled) for the footprints in the layout excerpt that follows; sources: Cadence DE-HDL packaged netlist, KiCad conversion of 04192023_DAF0TMB3IC0_F0TG_MB_C_brd_V02_OCP.brd

R6099  Q_RES  0 5% CHIP  pkg 0402LF  page 190 : A = PWRGD_P3V3_AUX_R1 ; B = PWRGD_P3V3_AUX
R1136  Q_RES  0 5% EMPTY  pkg 0402LF  page 134 : A = HP_LVC3_OCP_V3_1_P12V_PWRGD ; B = P3V3_OCP_EN_1_R

(kicad_pcb
	(version 20260206)
	(generator "pcbnew")
	(generator_version "10.0")
	(general
		(thickness 1.6)
		(legacy_teardrops no)
	)
	(paper "A4")
	(title_block
		(title "04192023_DAF0TMB3IC0_F0TG_MB_C_brd_V02_OCP.brd")
		(comment 1 "Grand Teton / footprints 2118-2119 of 8354")
	)
	(layers
		(0 "F.Cu" signal "TOP")
		(4 "In1.Cu" signal "GND")
		(6 "In2.Cu" signal "IN1")
		(8 "In3.Cu" signal "GND1")
		(10 "In4.Cu" signal "IN2")
		(12 "In5.Cu" signal "GND2")
		(14 "In6.Cu" signal "IN3")
		(16 "In7.Cu" signal "GND3")
		(18 "In8.Cu" signal "VCC")
		(20 "In9.Cu" signal "VCC1")
		(22 "In10.Cu" signal "GND4")
		(24 "In11.Cu" signal "IN4")
		(26 "In12.Cu" signal "GND5")
		(28 "In13.Cu" signal "IN5")
		(30 "In14.Cu" signal "GND6")
		(32 "In15.Cu" signal "IN6")
		(34 "In16.Cu" signal "GND7")
		(2 "B.Cu" signal "BOTTOM")
		(9 "F.Adhes" user "F.Adhesive")
		(11 "B.Adhes" user "B.Adhesive")
		(13 "F.Paste" user "Package Geometry/Pastemask Top")
		(15 "B.Paste" user "Package Geometry/Pastemask Bottom")
		(5 "F.SilkS" user "Ref Des/Silkscreen Top")
		(7 "B.SilkS" user "Ref Des/Silkscreen Bottom")
		(1 "F.Mask" user "Board Geometry/Soldermask Top")
		(3 "B.Mask" user "Board Geometry/Soldermask Bottom")
		(17 "Dwgs.User" user "User.Drawings")
		(19 "Cmts.User" user "User.Comments")
		(21 "Eco1.User" user "User.Eco1")
		(23 "Eco2.User" user "User.Eco2")
		(25 "Edge.Cuts" user "Board Geometry/Outline")
		(27 "Margin" user)
		(31 "F.CrtYd" user "Package Geometry/Place Bound Top")
		(29 "B.CrtYd" user "Package Geometry/Place Bound Bottom")
		(35 "F.Fab" user "Ref Des/Assembly Top")
		(33 "B.Fab" user "Ref Des/Assembly Bottom")
	)
	(footprint ""
		(layer "F.Cu")
		(at 460.174594 -45.477176 -90)
		(property "Reference" "R6099"
			(at 0 0 270)
			(layer "F.SilkS")
			(hide yes)
			(effects
				(font
					(size 1.27 1.27)
				)
			)
		)
		(property "Value" ""
			(at 0 0 270)
			(layer "F.Fab")
			(effects
				(font
					(size 1.27 1.27)
				)
			)
		)
		(duplicate_pad_numbers_are_jumpers no)
		(fp_line
			(start -0.7874 0.4064)
			(end -0.7874 -0.4064)
			(stroke
				(width 0.1524)
				(type default)
			)
			(layer "F.SilkS")
		)
		(fp_line
			(start 0.7874 0.4064)
			(end -0.7874 0.4064)
			(stroke
				(width 0.1524)
				(type default)
			)
			(layer "F.SilkS")
		)
		(fp_line
			(start -0.7874 -0.4064)
			(end 0.7874 -0.4064)
			(stroke
				(width 0.1524)
				(type default)
			)
			(layer "F.SilkS")
		)
		(fp_line
			(start 0.7874 -0.4064)
			(end 0.7874 0.4064)
			(stroke
				(width 0.1524)
				(type default)
			)
			(layer "F.SilkS")
		)
		(fp_line
			(start -0.67945 0.3048)
			(end -0.67945 -0.305054)
			(stroke
				(width 0.1)
				(type default)
			)
			(layer "F.Fab")
		)
		(fp_line
			(start -0.12065 0.3048)
			(end -0.67945 0.3048)
			(stroke
				(width 0.1)
				(type default)
			)
			(layer "F.Fab")
		)
		(fp_line
			(start 0.120396 0.3048)
			(end 0.120396 0.2794)
			(stroke
				(width 0.1)
				(type default)
			)
			(layer "F.Fab")
		)
		(fp_line
			(start 0.67945 0.3048)
			(end 0.120396 0.3048)
			(stroke
				(width 0.1)
				(type default)
			)
			(layer "F.Fab")
		)
		(fp_line
			(start -0.12065 0.2794)
			(end -0.12065 0.3048)
			(stroke
				(width 0.1)
				(type default)
			)
			(layer "F.Fab")
		)
		(fp_line
			(start 0.120396 0.2794)
			(end -0.12065 0.2794)
			(stroke
				(width 0.1)
				(type default)
			)
			(layer "F.Fab")
		)
		(fp_line
			(start -0.12065 -0.2794)
			(end 0.12065 -0.2794)
			(stroke
				(width 0.1)
				(type default)
			)
			(layer "F.Fab")
		)
		(fp_line
			(start 0.12065 -0.2794)
			(end 0.12065 -0.3048)
			(stroke
				(width 0.1)
				(type default)
			)
			(layer "F.Fab")
		)
		(fp_line
			(start 0.12065 -0.3048)
			(end 0.67945 -0.3048)
			(stroke
				(width 0.1)
				(type default)
			)
			(layer "F.Fab")
		)
		(fp_line
			(start 0.67945 -0.3048)
			(end 0.67945 0.3048)
			(stroke
				(width 0.1)
				(type default)
			)
			(layer "F.Fab")
		)
		(fp_line
			(start -0.67945 -0.305054)
			(end -0.12065 -0.305054)
			(stroke
				(width 0.1)
				(type default)
			)
			(layer "F.Fab")
		)
		(fp_line
			(start -0.12065 -0.305054)
			(end -0.12065 -0.2794)
			(stroke
				(width 0.1)
				(type default)
			)
			(layer "F.Fab")
		)
		(pad "1" smd circle
			(at -0.40005 0 270)
			(size 0 0)
			(layers "F.Cu" "F.Mask" "F.Paste")
			(net "PWRGD_P3V3_AUX_R1")
		)
		(pad "2" smd circle
			(at 0.40005 0 270)
			(size 0 0)
			(layers "F.Cu" "F.Mask" "F.Paste")
			(net "PWRGD_P3V3_AUX")
		)
	)
	(footprint ""
		(layer "F.Cu")
		(at 453.169782 -41.757346 90)
		(property "Reference" "R1136"
			(at 0 0 90)
			(layer "F.SilkS")
			(hide yes)
			(effects
				(font
					(size 1.27 1.27)
				)
			)
		)
		(property "Value" ""
			(at 0 0 90)
			(layer "F.Fab")
			(effects
				(font
					(size 1.27 1.27)
				)
			)
		)
		(duplicate_pad_numbers_are_jumpers no)
		(fp_line
			(start 0.7874 -0.4064)
			(end 0.7874 0.4064)
			(stroke
				(width 0.1524)
				(type default)
			)
			(layer "F.SilkS")
		)
		(fp_line
			(start -0.7874 -0.4064)
			(end 0.7874 -0.4064)
			(stroke
				(width 0.1524)
				(type default)
			)
			(layer "F.SilkS")
		)
		(fp_line
			(start 0.7874 0.4064)
			(end -0.7874 0.4064)
			(stroke
				(width 0.1524)
				(type default)
			)
			(layer "F.SilkS")
		)
		(fp_line
			(start -0.7874 0.4064)
			(end -0.7874 -0.4064)
			(stroke
				(width 0.1524)
				(type default)
			)
			(layer "F.SilkS")
		)
		(fp_line
			(start -0.12065 -0.305054)
			(end -0.12065 -0.2794)
			(stroke
				(width 0.1)
				(type default)
			)
			(layer "F.Fab")
		)
		(fp_line
			(start -0.67945 -0.305054)
			(end -0.12065 -0.305054)
			(stroke
				(width 0.1)
				(type default)
			)
			(layer "F.Fab")
		)
		(fp_line
			(start 0.67945 -0.3048)
			(end 0.67945 0.3048)
			(stroke
				(width 0.1)
				(type default)
			)
			(layer "F.Fab")
		)
		(fp_line
			(start 0.12065 -0.3048)
			(end 0.67945 -0.3048)
			(stroke
				(width 0.1)
				(type default)
			)
			(layer "F.Fab")
		)
		(fp_line
			(start 0.12065 -0.2794)
			(end 0.12065 -0.3048)
			(stroke
				(width 0.1)
				(type default)
			)
			(layer "F.Fab")
		)
		(fp_line
			(start -0.12065 -0.2794)
			(end 0.12065 -0.2794)
			(stroke
				(width 0.1)
				(type default)
			)
			(layer "F.Fab")
		)
		(fp_line
			(start 0.120396 0.2794)
			(end -0.12065 0.2794)
			(stroke
				(width 0.1)
				(type default)
			)
			(layer "F.Fab")
		)
		(fp_line
			(start -0.12065 0.2794)
			(end -0.12065 0.3048)
			(stroke
				(width 0.1)
				(type default)
			)
			(layer "F.Fab")
		)
		(fp_line
			(start 0.67945 0.3048)
			(end 0.120396 0.3048)
			(stroke
				(width 0.1)
				(type default)
			)
			(layer "F.Fab")
		)
		(fp_line
			(start 0.120396 0.3048)
			(end 0.120396 0.2794)
			(stroke
				(width 0.1)
				(type default)
			)
			(layer "F.Fab")
		)
		(fp_line
			(start -0.12065 0.3048)
			(end -0.67945 0.3048)
			(stroke
				(width 0.1)
				(type default)
			)
			(layer "F.Fab")
		)
		(fp_line
			(start -0.67945 0.3048)
			(end -0.67945 -0.305054)
			(stroke
				(width 0.1)
				(type default)
			)
			(layer "F.Fab")
		)
		(pad "1" smd circle
			(at -0.40005 0 90)
			(size 0 0)
			(layers "F.Cu" "F.Mask" "F.Paste")
			(net "HP_LVC3_OCP_V3_1_P12V_PWRGD")
		)
		(pad "2" smd circle
			(at 0.40005 0 90)
			(size 0 0)
			(layers "F.Cu" "F.Mask" "F.Paste")
			(net "P3V3_OCP_EN_1_R")
		)
	)
)
